# BASEBOARD_FAB2 (Tioga Pass) — schematic netlist excerpt (pin names and nets, part order shuffled) for the footprints in the layout excerpt that follows; sources: Cadence DE-HDL packaged netlist, KiCad conversion of Wiwynn_Tioga_Pass_MB.brd

C2L8  CAP_A  1.0UF 6.3V 10% X6S  pkg 0402V  page 235 : A = VR_PVNN_PCH_VDD ; B = GND
R25W105  RES  4.75K 1% EMPTY  pkg 0402  page 150 : A = P3V3_STBY ; B = PU_JTAG_BMC_RTCK
C2L12  CAP_A  0.01UF 25V 10% X7R  pkg 0402V  page 173 : A = SATA6G_PCH_PCIE_UP_SATA_RXP<5> ; B = SATA6G_P5_RX_C_DP

(kicad_pcb
	(version 20260206)
	(generator "pcbnew")
	(generator_version "10.0")
	(general
		(thickness 1.6)
		(legacy_teardrops no)
	)
	(paper "A4")
	(title_block
		(title "Wiwynn_Tioga_Pass_MB.brd")
		(comment 1 "Tioga Pass / footprints 3999-4001 of 4770")
	)
	(layers
		(0 "F.Cu" signal "TOP")
		(4 "In1.Cu" signal "L2GND")
		(6 "In2.Cu" signal "L3")
		(8 "In3.Cu" signal "L4GND")
		(10 "In4.Cu" signal "L5")
		(12 "In5.Cu" signal "L6GND")
		(14 "In6.Cu" signal "L7VCC")
		(16 "In7.Cu" signal "L8VCC")
		(18 "In8.Cu" signal "L9GND")
		(20 "In9.Cu" signal "L10")
		(22 "In10.Cu" signal "L11GND")
		(24 "In11.Cu" signal "L12")
		(26 "In12.Cu" signal "L13GND")
		(2 "B.Cu" signal "BOTTOM")
		(9 "F.Adhes" user "F.Adhesive")
		(11 "B.Adhes" user "B.Adhesive")
		(13 "F.Paste" user "Package Geometry/Pastemask Top")
		(15 "B.Paste" user "Package Geometry/Pastemask Bottom")
		(5 "F.SilkS" user "Ref Des/Silkscreen Top")
		(7 "B.SilkS" user "Ref Des/Silkscreen Bottom")
		(1 "F.Mask" user "Board Geometry/Soldermask Top")
		(3 "B.Mask" user "Board Geometry/Soldermask Bottom")
		(17 "Dwgs.User" user "User.Drawings")
		(19 "Cmts.User" user "User.Comments")
		(21 "Eco1.User" user "User.Eco1")
		(23 "Eco2.User" user "User.Eco2")
		(25 "Edge.Cuts" user "Board Geometry/Outline")
		(27 "Margin" user)
		(31 "F.CrtYd" user "Package Geometry/Place Bound Top")
		(29 "B.CrtYd" user "Package Geometry/Place Bound Bottom")
		(35 "F.Fab" user "Ref Des/Assembly Top")
		(33 "B.Fab" user "Ref Des/Assembly Bottom")
	)
	(footprint ""
		(layer "B.Cu")
		(at 393.286234 -152.73274 90)
		(property "Reference" "C2L8"
			(at 0 0 90)
			(layer "B.SilkS")
			(hide yes)
			(effects
				(font
					(size 1.27 1.27)
				)
				(justify mirror)
			)
		)
		(property "Value" ""
			(at 0 0 90)
			(layer "B.Fab")
			(effects
				(font
					(size 1.27 1.27)
				)
				(justify mirror)
			)
		)
		(duplicate_pad_numbers_are_jumpers no)
		(fp_poly
			(pts
				(xy -0.3048 -0.1016) (xy -0.3048 0.9906) (xy 0.3048 0.9906) (xy 0.3048 -0.1016)
			)
			(stroke
				(width 0)
				(type default)
			)
			(fill no)
			(layer "B.CrtYd")
		)
		(fp_line
			(start 0.3048 -0.1016)
			(end 0.3048 0.9906)
			(stroke
				(width 0.1)
				(type default)
			)
			(layer "B.Fab")
		)
		(fp_line
			(start -0.3048 -0.1016)
			(end 0.3048 -0.1016)
			(stroke
				(width 0.1)
				(type default)
			)
			(layer "B.Fab")
		)
		(fp_line
			(start 0.3048 0.9906)
			(end -0.3048 0.9906)
			(stroke
				(width 0.1)
				(type default)
			)
			(layer "B.Fab")
		)
		(fp_line
			(start -0.3048 0.9906)
			(end -0.3048 -0.1016)
			(stroke
				(width 0.1)
				(type default)
			)
			(layer "B.Fab")
		)
		(pad "1" smd rect
			(at 0 0 270)
			(size 0.508 0.508)
			(layers "B.Cu" "B.Mask" "B.Paste")
			(net "VR_PVNN_PCH_VDD")
		)
		(pad "2" smd rect
			(at 0 0.889 270)
			(size 0.508 0.508)
			(layers "B.Cu" "B.Mask" "B.Paste")
			(net "GND")
		)
		(zone
			(layer "B.Cu")
			(hatch none 0.5)
			(connect_pads
				(clearance 0)
			)
			(min_thickness 0.25)
			(keepout
				(tracks allowed)
				(vias not_allowed)
				(pads allowed)
				(copperpour not_allowed)
				(footprints allowed)
			)
			(placement
				(enabled no)
				(sheetname "")
			)
			(fill
				(thermal_gap 0.5)
				(thermal_bridge_width 0.5)
				(island_removal_mode 0)
			)
			(polygon
				(pts
					(xy 393.540234 -152.98674) (xy 393.540234 -152.47874) (xy 393.921234 -152.47874) (xy 393.921234 -152.98674)
				)
			)
		)
		(zone
			(layer "B.Cu")
			(hatch none 0.5)
			(connect_pads
				(clearance 0)
			)
			(min_thickness 0.25)
			(keepout
				(tracks not_allowed)
				(vias allowed)
				(pads allowed)
				(copperpour not_allowed)
				(footprints allowed)
			)
			(placement
				(enabled no)
				(sheetname "")
			)
			(fill
				(thermal_gap 0.5)
				(thermal_bridge_width 0.5)
				(island_removal_mode 0)
			)
			(polygon
				(pts
					(xy 393.921234 -152.98674) (xy 393.921234 -152.47874) (xy 393.540234 -152.47874) (xy 393.540234 -152.98674)
				)
			)
		)
	)
	(footprint ""
		(layer "B.Cu")
		(at 401.599146 -36.331652 90)
		(property "Reference" "R25W105"
			(at 0.8382 -0.67818 90)
			(unlocked yes)
			(layer "B.SilkS")
			(effects
				(font
					(size 0.4064 0.254)
					(thickness 0.1524)
				)
				(justify left mirror)
			)
		)
		(property "Value" ""
			(at 0 0 90)
			(layer "B.Fab")
			(effects
				(font
					(size 1.27 1.27)
				)
				(justify mirror)
			)
		)
		(duplicate_pad_numbers_are_jumpers no)
		(fp_poly
			(pts
				(xy 0.2794 -0.1016) (xy -0.2794 -0.1016) (xy -0.2794 0.9906) (xy 0.2794 0.9906)
			)
			(stroke
				(width 0)
				(type default)
			)
			(fill no)
			(layer "B.CrtYd")
		)
		(fp_line
			(start 0.2794 -0.1016)
			(end 0.2794 0.9906)
			(stroke
				(width 0.1)
				(type default)
			)
			(layer "B.Fab")
		)
		(fp_line
			(start -0.2794 -0.1016)
			(end 0.2794 -0.1016)
			(stroke
				(width 0.1)
				(type default)
			)
			(layer "B.Fab")
		)
		(fp_line
			(start 0.2794 0.9906)
			(end -0.2794 0.9906)
			(stroke
				(width 0.1)
				(type default)
			)
			(layer "B.Fab")
		)
		(fp_line
			(start -0.2794 0.9906)
			(end -0.2794 -0.1016)
			(stroke
				(width 0.1)
				(type default)
			)
			(layer "B.Fab")
		)
		(pad "1" smd rect
			(at 0 0 270)
			(size 0.508 0.508)
			(layers "B.Cu" "B.Mask" "B.Paste")
			(net "P3V3_STBY")
		)
		(pad "2" smd rect
			(at 0 0.889 270)
			(size 0.508 0.508)
			(layers "B.Cu" "B.Mask" "B.Paste")
			(net "PU_JTAG_BMC_RTCK")
		)
		(zone
			(layer "B.Cu")
			(hatch none 0.5)
			(connect_pads
				(clearance 0)
			)
			(min_thickness 0.25)
			(keepout
				(tracks allowed)
				(vias not_allowed)
				(pads allowed)
				(copperpour not_allowed)
				(footprints allowed)
			)
			(placement
				(enabled no)
				(sheetname "")
			)
			(fill
				(thermal_gap 0.5)
				(thermal_bridge_width 0.5)
				(island_removal_mode 0)
			)
			(polygon
				(pts
					(xy 401.853146 -36.585652) (xy 401.853146 -36.077652) (xy 402.234146 -36.077652) (xy 402.234146 -36.585652)
				)
			)
		)
		(zone
			(layer "B.Cu")
			(hatch none 0.5)
			(connect_pads
				(clearance 0)
			)
			(min_thickness 0.25)
			(keepout
				(tracks not_allowed)
				(vias allowed)
				(pads allowed)
				(copperpour not_allowed)
				(footprints allowed)
			)
			(placement
				(enabled no)
				(sheetname "")
			)
			(fill
				(thermal_gap 0.5)
				(thermal_bridge_width 0.5)
				(island_removal_mode 0)
			)
			(polygon
				(pts
					(xy 402.234146 -36.585652) (xy 402.234146 -36.077652) (xy 401.853146 -36.077652) (xy 401.853146 -36.585652)
				)
			)
		)
	)
	(footprint ""
		(layer "B.Cu")
		(at 410.464 -152.273 90)
		(property "Reference" "C2L12"
			(at 0 0 90)
			(layer "B.SilkS")
			(hide yes)
			(effects
				(font
					(size 1.27 1.27)
				)
				(justify mirror)
			)
		)
		(property "Value" ""
			(at 0 0 90)
			(layer "B.Fab")
			(effects
				(font
					(size 1.27 1.27)
				)
				(justify mirror)
			)
		)
		(duplicate_pad_numbers_are_jumpers no)
		(fp_poly
			(pts
				(xy -0.3048 -0.1016) (xy -0.3048 0.9906) (xy 0.3048 0.9906) (xy 0.3048 -0.1016)
			)
			(stroke
				(width 0)
				(type default)
			)
			(fill no)
			(layer "B.CrtYd")
		)
		(fp_line
			(start 0.3048 -0.1016)
			(end 0.3048 0.9906)
			(stroke
				(width 0.1)
				(type default)
			)
			(layer "B.Fab")
		)
		(fp_line
			(start -0.3048 -0.1016)
			(end 0.3048 -0.1016)
			(stroke
				(width 0.1)
				(type default)
			)
			(layer "B.Fab")
		)
		(fp_line
			(start 0.3048 0.9906)
			(end -0.3048 0.9906)
			(stroke
				(width 0.1)
				(type default)
			)
			(layer "B.Fab")
		)
		(fp_line
			(start -0.3048 0.9906)
			(end -0.3048 -0.1016)
			(stroke
				(width 0.1)
				(type default)
			)
			(layer "B.Fab")
		)
		(pad "1" smd rect
			(at 0 0 270)
			(size 0.508 0.508)
			(layers "B.Cu" "B.Mask" "B.Paste")
			(net "SATA6G_PCH_PCIE_UP_SATA_RXP<5>")
		)
		(pad "2" smd rect
			(at 0 0.889 270)
			(size 0.508 0.508)
			(layers "B.Cu" "B.Mask" "B.Paste")
			(net "SATA6G_P5_RX_C_DP")
		)
		(zone
			(layer "B.Cu")
			(hatch none 0.5)
			(connect_pads
				(clearance 0)
			)
			(min_thickness 0.25)
			(keepout
				(tracks allowed)
				(vias not_allowed)
				(pads allowed)
				(copperpour not_allowed)
				(footprints allowed)
			)
			(placement
				(enabled no)
				(sheetname "")
			)
			(fill
				(thermal_gap 0.5)
				(thermal_bridge_width 0.5)
				(island_removal_mode 0)
			)
			(polygon
				(pts
					(xy 410.718 -152.527) (xy 410.718 -152.019) (xy 411.099 -152.019) (xy 411.099 -152.527)
				)
			)
		)
		(zone
			(layer "B.Cu")
			(hatch none 0.5)
			(connect_pads
				(clearance 0)
			)
			(min_thickness 0.25)
			(keepout
				(tracks not_allowed)
				(vias allowed)
				(pads allowed)
				(copperpour not_allowed)
				(footprints allowed)
			)
			(placement
				(enabled no)
				(sheetname "")
			)
			(fill
				(thermal_gap 0.5)
				(thermal_bridge_width 0.5)
				(island_removal_mode 0)
			)
			(polygon
				(pts
					(xy 411.099 -152.527) (xy 411.099 -152.019) (xy 410.718 -152.019) (xy 410.718 -152.527)
				)
			)
		)
	)
)
